# Wiwynn_Honey Badger_DPB_8L_Stackup_20150121.xlsx — Wiwynn (pcb-stackup)
|  |  |  |  |  |  |  |  |  |  | Single Ended Type(mil) |  |  |  |  | Differential Type(mil) |  |  |  |  |  |
|  |  |  |  |  |  |  |  |  | Imp | 50 |  |  |  | Imp | 100 |  |  |  |  |  |
|  |  |  |  |  |  |  |  |  | Variation | Inner /Outer ±5Ω |  |  |  | Variation | Inner 10% / Outer 10% |  |  |  |  |  |
|  |  |  |  |  |  |  |  |  | Bus | MISC |  |  |  | Bus | SAS/SATA |  |  |  |  |  |
|  |  |  |  |  |  |  |  |  | Type | SE |  |  |  | Type | DP |  |  |  |  |  |
| Layer |  |  | Thickness |  | Glass style | Er |  | Df(1G) | Layers | All |  |  |  | Layers | All |  |  |  |  |  |
|  |  | Cu oz | Wiwynn | Vender |  | Wiwynn | Vender |  |  | Wiwynn |  | Vender |  |  | Wiwynn |  |  | Vender |  |  |
|  | Mask |  | 0.5 |  |  | 3.8 |  |  |  | Width | Imp | Width | Imp |  | Width | Space | Imp | Width | Space | Imp |
| Top | Signal | 0.5 oz + plating | 1.9 |  |  |  |  |  | S1 | 4 |  |  |  | S1 | 4 | 9 |  |  |  |  |
|  | Prepreg |  | 2.7 |  |  | 4 |  |  |  |  |  |  |  |  |  |  |  |  |  |  |
| L2 | GND | 2 oz | 2.6 |  |  |  |  |  | G2 | Reference layer |  | Reference layer |  | G2 | Reference layer |  |  | Reference layer |  |  |
|  | Core |  | 4 |  |  | 4 |  |  |  |  |  |  |  |  |  |  |  |  |  |  |
| L3 | Signal | 1 oz | 1.3 |  |  |  |  |  | S3 | 4.5 |  |  |  | S3 | 4 | 8 |  |  |  |  |
|  | Prepreg |  | 25 |  |  | 4.5 |  |  |  |  |  |  |  |  |  |  |  |  |  |  |
| L4 | PWR | 2 | 2.6 |  |  |  |  |  | P4 | Reference layer |  | Reference layer |  | P4 | Reference layer |  |  | Reference layer |  |  |
|  | Core |  | 4 |  |  | 4 |  |  |  |  |  |  |  |  |  |  |  |  |  |  |
| L5 | PWR | 2 | 2.6 |  |  |  |  |  | P5 | Reference layer |  | Reference layer |  | P5 | Reference layer |  |  | Reference layer |  |  |
|  | Prepreg |  | 25 |  |  | 4.5 |  |  |  |  |  |  |  |  |  |  |  |  |  |  |
| L6 | Signal | 1 oz | 1.3 |  |  |  |  |  | S6 | 4.5 |  |  |  | S6 | 4 | 8 |  |  |  |  |
|  | Core |  | 4 |  |  | 4 |  |  |  |  |  |  |  |  |  |  |  |  |  |  |
| L7 | GND | 2 oz | 2.6 |  |  |  |  |  | G7 | Reference layer |  | Reference layer |  | G7 | Reference layer |  |  | Reference layer |  |  |
|  | Prepreg |  | 2.7 |  |  | 4 |  |  |  |  |  |  |  |  |  |  |  |  |  |  |
| Bottom | Signal | 0.5 oz + plating | 1.9 |  |  |  |  |  | S8 | 4 |  |  |  | S8 | 4 | 9 |  |  |  |  |
|  | Mask |  | 0.5 |  |  | 3.8 |  |  |  |  |  |  |  |  |  |  |  |  |  |  |
| Thickness requirement: 2.16±10% mm |  | mil | 85.2 |  | +/-10% |  |  |  |  |  |  |  |  |  |  |  |  |  |  |  |
|  |  | mm | 2.1640843281686566 |  |  |  |  |  |  |  |  |  |  |  |  |  |  |  |  |  |
